# T6G (Grand Teton) — schematic parts with pin connectivity, parts 8082–8111 of 8303; source: Cadence DE-HDL packaged netlist (pstxprt.dat, pstxnet.dat, pstchip.dat)

U26  GENOA_SP5  SOCKET6096_13568-001 IO  pkg SOCKET6096_93-4X120-45XA  page 37  (pins 6049-6096 of 6096)
  Y26  VSS_Y26  POWER  = GND
  Y27  VSS_Y27  POWER  = GND
  Y28  VSS_Y28  POWER  = GND
  Y29  TEST5_CCD11  TRI  = TP_CPU1_TEST5_CCD11
  Y30  TEST5_CCD3  TRI  = TP_CPU1_TEST5_CCD3
  Y31  VSS_Y31  POWER  = GND
  Y32  VSS_Y32  POWER  = GND
  Y33  VSS_Y33  POWER  = GND
  Y34  VSS_Y34  POWER  = GND
  Y35  VDDCR_CPU0_Y35  POWER  = PVDDCR_CPU0_P1
  Y36  VDDCR_CPU0_Y36  POWER  = PVDDCR_CPU0_P1
  Y37  VSS_Y37  POWER  = GND
  Y39  VSS_Y39  POWER  = GND
  Y40  VDDCR_CPU0_Y40  POWER  = PVDDCR_CPU0_P1
  Y41  VDDCR_CPU0_Y41  POWER  = PVDDCR_CPU0_P1
  Y42  VSS_Y42  POWER  = GND
  Y43  VSS_Y43  POWER  = GND
  Y44  VSS_Y44  POWER  = GND
  Y45  VSS_Y45  POWER  = GND
  Y46  TEST6_CCD3  OUT  = TP_CPU1_TEST6_CCD3
  Y47  TEST5_CCD8  TRI  = TP_CPU1_TEST5_CCD8
  Y48  VSS_Y48  POWER  = GND
  Y49  VSS_Y49  POWER  = GND
  Y50  VSS_Y50  POWER  = GND
  Y51  VSS_Y51  POWER  = GND
  Y52  VSS_Y52  POWER  = GND
  Y53  VSS_Y53  POWER  = GND
  Y54  VSS_Y54  POWER  = GND
  Y55  MCA_DQS_L7  BI  = M_C_CPU1_SA_DQS_DN<7>
  Y56  MCA_DQS_L2  BI  = M_C_CPU1_SA_DQS_DN<2>
  Y57  VDDIO_Y57  POWER  = PVDDIO_P1
  Y58  MDA_DQS_L7  BI  = M_D_CPU1_SA_DQS_DN<7>
  Y59  VSS_Y59  POWER  = GND
  Y60  MDA_DQS_L2  BI  = M_D_CPU1_SA_DQS_DN<2>
  Y61  VSS_Y61  POWER  = GND
  Y62  MBA_DQS_L7  BI  = M_B_CPU1_SA_DQS_DN<7>
  Y63  MBA_DQS_L2  BI  = M_B_CPU1_SA_DQS_DN<2>
  Y64  VDDIO_Y64  POWER  = PVDDIO_P1
  Y65  MFA_DQS_L7  BI  = M_F_CPU1_SA_DQS_DN<7>
  Y66  VSS_Y66  POWER  = GND
  Y67  MFA_DQS_L2  BI  = M_F_CPU1_SA_DQS_DN<2>
  Y68  VSS_Y68  POWER  = GND
  Y69  MEA_DQS_L7  BI  = M_E_CPU1_SA_DQS_DN<7>
  Y70  MEA_DQS_L2  BI  = M_E_CPU1_SA_DQS_DN<2>
  Y71  VDDIO_Y71  POWER  = PVDDIO_P1
  Y72  MAA_DQS_L7  BI  = M_A_CPU1_SA_DQS_DN<7>
  Y73  VSS_Y73  POWER  = GND
  Y74  MAA_DQS_L2  BI  = M_A_CPU1_SA_DQS_DN<2>

U27  PCA9617ADP  IC  pkg TSSOP8_3XB  page 34
  1  VCCA  POWER  = PVDD18_S5_P0
  2  SCLA  BI  = SMB_CPU0_4_SCL
  3  SDAA  BI  = SMB_CPU0_4_SDA
  4  GND  POWER  = GND
  5  EN  IN  = TP_U27_EN
  6  SDAB  BI  = SMB_CPU0_4_XLTR_SDA
  7  SCLB  BI  = SMB_CPU0_4_XLTR_SCL
  8  VCCB  POWER  = P3V3_AUX

U28  SN74LVC1G07DBVR  IC  pkg SMLF  page 136
  1  NC  TRI  = NC
  2  A  IN  = HP_LVC3_OCP_V3_1_P12V_R_PWRGD
  3  GND  POWER  = GND
  4  Y  OCA  = P12V_OCP_V3_1_PLD_R_PWRGD
  5  VCC  POWER  = P3V3_AUX

U29  SN74LVC2G07DCKR  IC  pkg SMLF  page 78
  1  \1a\  IN  = PWRGD_CPU0_PWROK
  2  GND  POWER  = GND
  3  \2a\  IN  = PWRGD_CPU0_PWROK
  4  \2y\  OUT  = PVDDCR_CPU1_P0_RESET_N
  5  VCC  POWER  = P1V8_AUX
  6  \1y\  OUT  = PVDDCR_CPU0_P0_RESET_N

U30  SN74LVC1G07DBVR  IC  pkg SMLF  page 136
  1  NC  TRI  = NC
  2  A  IN  = OCP_V3_1_P3V3_R2_PWRGD
  3  GND  POWER  = GND
  4  Y  OCA  = OCP_V3_1_P3V3_PLD_PWRGD
  5  VCC  POWER  = P3V3_AUX

U31  74LVC1G08W57  74LVC1G08W5-7 IC  pkg SOT25-5_0-95_3X1-6  page 142
  1  A  IN  = P12V_OCP_V3_2_EN_R3
  2  B  IN  = HP_LVC3_OCP_V3_2_PRSNT2
  3  GND  POWER  = GND
  4  Y  OUT  = P12V_OCP_V3_2_BUF_EN
  5  VCC  POWER  = P3V3_AUX

U32  MOSFET_N  BSS138K IC  pkg SMLF  page 142
  D  DRAIN  OUT  = HP_LVC3_OCP_V3_2_PRSNT2
  G  GATE  IN  = HP_LVC3_OCP_V3_2_PRSNT2_N
  S  SOURCE  BI  = GND

U33  SN74LVC1G07DBVR  IC  pkg SMLF  page 142
  1  NC  TRI  = NC
  2  A  IN  = HP_LVC3_OCP_V3_2_P12V_R_PWRGD
  3  GND  POWER  = GND
  4  Y  OCA  = P12V_OCP_V3_2_PLD_R_PWRGD
  5  VCC  POWER  = P3V3_AUX

U34  SN74LVC1G07DBVR  IC  pkg SMLF  page 142
  1  NC  TRI  = NC
  2  A  IN  = OCP_V3_2_P3V3_R2_PWRGD
  3  GND  POWER  = GND
  4  Y  OCA  = OCP_V3_2_P3V3_PLD_PWRGD
  5  VCC  POWER  = P3V3_AUX

U35  74LVC1G08W57  74LVC1G08W5-7 IC  pkg SOT25-5_0-95_3X1-6  page 142
  1  A  IN  = RST_PERST_OCP_V3_2_R_N
  2  B  IN  = HP_LVC3_OCP_V3_2_PWRGD
  3  GND  POWER  = GND
  4  Y  OUT  = RST_PERST_OCP_V3_2_BUF_R_N
  5  VCC  POWER  = P3V3_AUX

U36  TCA9548APWR  IC  pkg TSSOP24XA  page 250
  1  A0  IN  = PCA9548_PCIE3_ADDR0
  2  A1  IN  = PCA9548_PCIE3_ADDR1
  3  \reset#\  IN  = PU_RST_SMB_PCIE0_N
  4  SD0  BI  = SMB_USB_CPU0_HUB1_SDA_R
  5  SC0  BI  = SMB_USB_CPU0_HUB1_SCL_R
  6  SD1  BI  = SMB_IOEXP_3V3AUX_SDA_R
  7  SC1  BI  = SMB_IOEXP_3V3AUX_SCL_R
  8  SD2  BI  = SMB_PCIE0_3V3AUX_SDA_R3
  9  SC2  BI  = SMB_PCIE0_3V3AUX_SCL_R3
  10  SD3  BI  = SMB_PCIE0_3V3AUX_SDA_R5
  11  SC3  BI  = SMB_PCIE0_3V3AUX_SCL_R5
  12  GND  POWER  = GND
  13  SD4  BI  = SMB_BMC_SWB_SDA_R4
  14  SC4  BI  = SMB_BMC_SWB_SCL_R4
  15  SD5  BI  = SMB_FRU_3V3AUX_SDA_R
  16  SC5  BI  = SMB_FRU_3V3AUX_SCL_R
  17  SD6  BI  = SMB_INA230_3V3AUX_SDA_R
  18  SC6  BI  = SMB_INA230_3V3AUX_SCL_R
  19  SD7  BI  = NC
  20  SC7  BI  = NC
  21  A2  IN  = PCA9548_PCIE3_ADDR2
  22  SCL  BI  = SMB_PCIE0_3V3AUX_SCL_R
  23  SDA  BI  = SMB_PCIE0_3V3AUX_SDA_R
  24  VCC  POWER  = P3V3_AUX

U37  74LVC1G32GW  IC  pkg SMLF  page 142
  1  I0  IN  = HP_LVC3_OCP_V3_2_PWRGD_R1
  2  I1  IN  = FM_OCP_V3_2_AUX_PWR_R_EN
  3  GND  POWER  = GND
  4  O  OUT  = OCP_V3_2_AUX_PWR_EN_R2
  5  VCC  POWER  = P3V3_AUX

U38  SN74LVC1G11DCKR  IC  pkg SC70-6_0-65_2X1-25  page 259
  1  A  IN  = PWRGD_P12V_MEM_CPU0_R
  2  GND  POWER  = GND
  3  B  IN  = PWRGD_P12V_MEM_CPU1_R
  4  Y  OUT  = PWRGD_P12V_MEM
  5  VCC  POWER  = P1V8_AUX
  6  C  IN  = PU_U38_6

U39  TCA9548APWR  IC  pkg TSSOP24XA  page 252
  1  A0  IN  = PCA9548_PCIE0_ADDR0
  2  A1  IN  = PCA9548_PCIE0_ADDR1
  3  \reset#\  IN  = PU_RST_SMB_PCIE2_N
  4  SD0  BI  = SMB_VR_3V3AUX_SDA_R6
  5  SC0  BI  = SMB_VR_3V3AUX_SCL_R6
  6  SD1  BI  = SMB_LM75_0_3V3AUX_SDA_R
  7  SC1  BI  = SMB_LM75_0_3V3AUX_SCL_R
  8  SD2  BI  = SMB_LM75_1_3V3AUX_SDA_R
  9  SC2  BI  = SMB_LM75_1_3V3AUX_SCL_R
  10  SD3  BI  = SMB_LM75_2_3V3AUX_SDA_R
  11  SC3  BI  = SMB_LM75_2_3V3AUX_SCL_R
  12  GND  POWER  = GND
  13  SD4  BI  = SMB_LM75_3_3V3AUX_SDA_R
  14  SC4  BI  = SMB_LM75_3_3V3AUX_SCL_R
  15  SD5  BI  = SMB_P12V_HSC_SDA_R
  16  SC5  BI  = SMB_P12V_HSC_SCL_R
  17  SD6  BI  = SMB_ADC_SDA
  18  SC6  BI  = SMB_ADC_SCL
  19  SD7  BI  = NC
  20  SC7  BI  = NC
  21  A2  IN  = PCA9548_PCIE0_ADDR2
  22  SCL  BI  = SMB_VR_SENSOR_3V3AUX_SCL_R
  23  SDA  BI  = SMB_VR_SENSOR_3V3AUX_SDA_R
  24  VCC  POWER  = P3V3_AUX

U40  SN74LVC2G07DCKR  IC  pkg SMLF  page 78
  1  \1a\  IN  = PWRGD_CPU1_PWROK
  2  GND  POWER  = GND
  3  \2a\  IN  = PWRGD_CPU1_PWROK
  4  \2y\  OUT  = PVDDCR_CPU1_P1_RESET_N
  5  VCC  POWER  = P1V8_AUX
  6  \1y\  OUT  = PVDDCR_CPU0_P1_RESET_N

U41  PI3CSW12ZUAEX  IC  pkg UQFN10_0-5_2X1-5  page 186
  1  \1d+\  BI  = SMB_RT_CPU1_P3_ROM_MUX_1D_SCL
  2  \1d-\  BI  = SMB_RT_CPU1_P3_ROM_MUX_1D_SDA
  3  \2d+\  BI  = SMB_RT_CPU1_P3_ROM_MUX_2D_SCL
  4  \2d-\  BI  = SMB_RT_CPU1_P3_ROM_MUX_2D_SDA
  5  GND  POWER  = GND
  6  \oe#\  IN  = RT_ROM_MUX3_OE_N
  7  \d-\  BI  = SMB_RT_CPU1_P3_ROM_R_SDA
  8  \d+\  BI  = SMB_RT_CPU1_P3_ROM_R_SCL
  9  S  IN  = FM_SMB_RT_ROM_MUX3_SEL
  10  VDD  POWER  = P3V3_AUX

U42  PI3CSW12ZUAEX  IC  pkg UQFN10_0-5_2X1-5  page 186
  1  \1d+\  BI  = SMB_RT_CPU1_P1_ROM_MUX_1D_SCL
  2  \1d-\  BI  = SMB_RT_CPU1_P1_ROM_MUX_1D_SDA
  3  \2d+\  BI  = SMB_RT_CPU1_P1_ROM_MUX_2D_SCL
  4  \2d-\  BI  = SMB_RT_CPU1_P1_ROM_MUX_2D_SDA
  5  GND  POWER  = GND
  6  \oe#\  IN  = RT_ROM_MUX2_OE_N
  7  \d-\  BI  = SMB_RT_CPU1_P1_ROM_R_SDA
  8  \d+\  BI  = SMB_RT_CPU1_P1_ROM_R_SCL
  9  S  IN  = FM_SMB_RT_ROM_MUX2_SEL
  10  VDD  POWER  = P3V3_AUX

U43  PI3CSW12ZUAEX  IC  pkg UQFN10_0-5_2X1-5  page 186
  1  \1d+\  BI  = SMB_RT_CPU1_P2_ROM_MUX_1D_SCL
  2  \1d-\  BI  = SMB_RT_CPU1_P2_ROM_MUX_1D_SDA
  3  \2d+\  BI  = SMB_RT_CPU1_P2_ROM_MUX_2D_SCL
  4  \2d-\  BI  = SMB_RT_CPU1_P2_ROM_MUX_2D_SDA
  5  GND  POWER  = GND
  6  \oe#\  IN  = RT_ROM_MUX4_OE_N
  7  \d-\  BI  = SMB_RT_CPU1_P2_ROM_R_SDA
  8  \d+\  BI  = SMB_RT_CPU1_P2_ROM_R_SCL
  9  S  IN  = FM_SMB_RT_ROM_MUX4_SEL
  10  VDD  POWER  = P3V3_AUX

U44  74LVC1G17GW  IC  pkg TSSOP5  page 145
  1  NC  TRI  = NC
  2  A  IN  = FM_LED_ACTIVE_E1S_0_R
  3  GND  POWER  = GND
  4  Y  OCA  = FM_LED_ACTIVE_E1S_0_R_BUF
  5  VCC  POWER  = P3V3_E1S_0

U45  PI3CSW12ZUAEX  IC  pkg UQFN10_0-5_2X1-5  page 186
  1  \1d+\  BI  = SMB_RT_CPU1_P0_ROM_MUX_1D_SCL
  2  \1d-\  BI  = SMB_RT_CPU1_P0_ROM_MUX_1D_SDA
  3  \2d+\  BI  = SMB_RT_CPU1_P0_ROM_MUX_2D_SCL
  4  \2d-\  BI  = SMB_RT_CPU1_P0_ROM_MUX_2D_SDA
  5  GND  POWER  = GND
  6  \oe#\  IN  = RT_ROM_MUX1_OE_N
  7  \d-\  BI  = SMB_RT_CPU1_P0_ROM_R_SDA
  8  \d+\  BI  = SMB_RT_CPU1_P0_ROM_R_SCL
  9  S  IN  = FM_SMB_RT_ROM_MUX1_SEL
  10  VDD  POWER  = P3V3_AUX

U46  PI3CSW12ZUAEX  IC  pkg UQFN10_0-5_2X1-5  page 186
  1  \1d+\  BI  = SMB_RT_CPU0_P3_ROM_MUX_1D_SCL
  2  \1d-\  BI  = SMB_RT_CPU0_P3_ROM_MUX_1D_SDA
  3  \2d+\  BI  = SMB_RT_CPU0_P3_ROM_MUX_2D_SCL
  4  \2d-\  BI  = SMB_RT_CPU0_P3_ROM_MUX_2D_SDA
  5  GND  POWER  = GND
  6  \oe#\  IN  = RT_ROM_MUX7_OE_N
  7  \d-\  BI  = SMB_RT_CPU0_P3_ROM_R_SDA
  8  \d+\  BI  = SMB_RT_CPU0_P3_ROM_R_SCL
  9  S  IN  = FM_SMB_RT_ROM_MUX7_SEL
  10  VDD  POWER  = P3V3_AUX

U47  PI3CSW12ZUAEX  IC  pkg UQFN10_0-5_2X1-5  page 186
  1  \1d+\  BI  = SMB_RT_CPU0_P2_ROM_MUX_1D_SCL
  2  \1d-\  BI  = SMB_RT_CPU0_P2_ROM_MUX_1D_SDA
  3  \2d+\  BI  = SMB_RT_CPU0_P2_ROM_MUX_2D_SCL
  4  \2d-\  BI  = SMB_RT_CPU0_P2_ROM_MUX_2D_SDA
  5  GND  POWER  = GND
  6  \oe#\  IN  = RT_ROM_MUX8_OE_N
  7  \d-\  BI  = SMB_RT_CPU0_P2_ROM_R_SDA
  8  \d+\  BI  = SMB_RT_CPU0_P2_ROM_R_SCL
  9  S  IN  = FM_SMB_RT_ROM_MUX8_SEL
  10  VDD  POWER  = P3V3_AUX

U48  PI3CSW12ZUAEX  IC  pkg UQFN10_0-5_2X1-5  page 186
  1  \1d+\  BI  = SMB_RT_CPU0_P1_ROM_MUX_1D_SCL
  2  \1d-\  BI  = SMB_RT_CPU0_P1_ROM_MUX_1D_SDA
  3  \2d+\  BI  = SMB_RT_CPU0_P1_ROM_MUX_2D_SCL
  4  \2d-\  BI  = SMB_RT_CPU0_P1_ROM_MUX_2D_SDA
  5  GND  POWER  = GND
  6  \oe#\  IN  = RT_ROM_MUX6_OE_N
  7  \d-\  BI  = SMB_RT_CPU0_P1_ROM_R_SDA
  8  \d+\  BI  = SMB_RT_CPU0_P1_ROM_R_SCL
  9  S  IN  = FM_SMB_RT_ROM_MUX6_SEL
  10  VDD  POWER  = P3V3_AUX

U49  PI3CSW12ZUAEX  IC  pkg UQFN10_0-5_2X1-5  page 186
  1  \1d+\  BI  = SMB_RT_CPU0_P0_ROM_MUX_1D_SCL
  2  \1d-\  BI  = SMB_RT_CPU0_P0_ROM_MUX_1D_SDA
  3  \2d+\  BI  = SMB_RT_CPU0_P0_ROM_MUX_2D_SCL
  4  \2d-\  BI  = SMB_RT_CPU0_P0_ROM_MUX_2D_SDA
  5  GND  POWER  = GND
  6  \oe#\  IN  = RT_ROM_MUX5_OE_N
  7  \d-\  BI  = SMB_RT_CPU0_P0_ROM_R_SDA
  8  \d+\  BI  = SMB_RT_CPU0_P0_ROM_R_SCL
  9  S  IN  = FM_SMB_RT_ROM_MUX5_SEL
  10  VDD  POWER  = P3V3_AUX

U50  MAX11617EEET  MAX11617EEE+T EMPTY  pkg QSOP16_0-635_4-9X3-89  page 258
  1  \ain11||ref\  BI  = MAX11617_2_VREF_R
  2  AIN10  BI  = GND
  3  AIN9  BI  = GND
  4  AIN8  BI  = GND
  5  AIN0  BI  = P5V_AUX_ADC_MAM
  6  AIN1  BI  = P1V8_AUX_ADC_MAM
  7  AIN2  BI  = P1V2_AUX_ADC_MAM
  8  AIN3  BI  = P1V8_CPU0_RT_1D_ADC_MAM
  9  AIN4  BI  = P1V8_CPU1_RT_1D_ADC_MAM
  10  AIN5  BI  = PVDD_33_S5_ADC_MAM
  11  AIN6  BI  = PVDD18_S5_P0_ADC_MAM
  12  AIN7  BI  = PVDD18_S5_P1_ADC_MAM
  13  SCL  BI  = SMB_SEN_MAM_2_3V3AUX_SCL
  14  SDA  BI  = SMB_SEN_MAM_2_3V3AUX_SDA
  15  GND  POWER  = GND
  16  VDD  POWER  = P3V3_MAX11617_2_VDD

U51  ADC128D818CIMTXNOPB  ADC128D818CIMTX/NOPB IC  pkg TSSOP16XC  page 258
  1  VREF  IN  = ADC128_2_VREF
  2  SDA  BI  = SMB_SEN_TIC_2_3V3AUX_SDA
  3  SCL  IN  = SMB_SEN_TIC_2_3V3AUX_SCL
  4  GND  POWER  = GND
  5  \v+\  POWER  = P3V3_ADC128_2_VCC
  6  \int#\  OUT  = TP_ADC128_2_INT
  7  A0  IN  = ADC128_2_A0
  8  A1  IN  = ADC128_2_A1
  9  IN7  IN  = PVDD18_S5_P1_ADC_TIC
  10  IN6  IN  = PVDD18_S5_P0_ADC_TIC
  11  IN5  IN  = PVDD_33_S5_ADC_TIC
  12  IN4  IN  = P1V8_CPU1_RT_1D_ADC_TIC
  13  IN3  IN  = P1V8_CPU0_RT_1D_ADC_TIC
  14  IN2  IN  = P1V2_AUX_ADC_TIC
  15  IN1  IN  = P1V8_AUX_ADC_TIC
  16  IN0  IN  = P5V_AUX_ADC_TIC

U52  ISL28022FRZT  ISL28022FRZ-T IC  pkg QFN16_TH_0-5_3X3XH  page 357
  1  A1  IN  = INA230_8_A1
  2  A0  IN  = INA230_8_A0
  3  \ext_clk||int\  BI  = P12V_E1S_0_ADC_ALERT_R
  4  \sda||smbdat\  BI  = SMB_INA230_8_3V3AUX_SDA_R1
  5  \scl|||smbclk\  IN  = SMB_INA230_8_3V3AUX_SCL_R1
  6  NC0  TRI  = NC_INA230_8_NC0
  7  NC1  TRI  = NC_INA230_8_NC1
  8  NC2  TRI  = NC_INA230_8_NC2
  9  VCC  POWER  = P3V3_AUX
  10  GND  POWER  = GND
  11  VBUS  POWER  = P12V_E1S_0
  12  VINM  IN  = VSENSE_P12V_INA230_8_INN
  13  VINP  IN  = VSENSE_P12V_INA230_8_INP
  14  NC3  TRI  = NC_INA230_8_NC3
  15  NC4  TRI  = NC_INA230_8_NC4
  16  NC5  TRI  = NC_INA230_8_NC5
  TH  TH_GND  POWER  = GND

U53  SN74AVC4T774PWR  IC  pkg TSSOP16XC  page 77
  1  DIR1  IN  = PVDD18_S5_P0
  2  DIR2  IN  = PVDD18_S5_P0
  3  A1  BI  = SPI_CPU0_CS0_N
  4  A2  BI  = SPI_CPU0_CLK
  5  A3  BI  = SPI_CPU0_CS1_N
  6  A4  BI  = SPI_CPU0_TPM_CS_N
  7  DIR3  IN  = PVDD18_S5_P0
  8  DIR4  IN  = PVDD18_S5_P0
  9  OE  IN  = ROM_SD_LS_OE
  10  GND  POWER  = GND
  11  B4  BI  = SPI_CPU0_LVC3_R_TPM_CS_N
  12  B3  BI  = SPI_CPU0_LVC3_CS1_N
  13  B2  BI  = SPI_CPU0_LVC3_CLK
  14  B1  BI  = SPI_CPU0_LVC3_CS0_N
  15  VCCB  POWER  = P3V3_AUX
  16  VCCA  POWER  = PVDD18_S5_P0

U54  PI4ULS3V304AZMAEX  IC  pkg UQFN12_0-4_2X1-7  page 77
  1  VCCA  POWER  = PVDD18_S5_P0
  2  A1  BI  = SPI_CPU0_R1_D3
  3  A2  BI  = SPI_CPU0_R1_D2
  4  A3  BI  = SPI_CPU0_R1_D0
  5  A4  BI  = SPI_CPU0_R1_D1
  6  GND  POWER  = GND
  7  B4  BI  = SPI_CPU0_LVC3_D1
  8  B3  BI  = SPI_CPU0_LVC3_D0
  9  B2  BI  = SPI_CPU0_LVC3_D2
  10  B1  BI  = SPI_CPU0_LVC3_D3
  11  VCCB  POWER  = P3V3_AUX
  12  EN  IN  = ROM_LS_EN

U55  ISL28022FRZT  ISL28022FRZ-T IC  pkg QFN16_TH_0-5_3X3XH  page 357
  1  A1  IN  = INA230_6_A1
  2  A0  IN  = INA230_6_A0
  3  \ext_clk||int\  BI  = P12V_OCP_SFF_ADC_ALERT_R
  4  \sda||smbdat\  BI  = SMB_INA230_6_3V3AUX_SDA_R1
  5  \scl|||smbclk\  IN  = SMB_INA230_6_3V3AUX_SCL_R1
  6  NC0  TRI  = NC_INA230_6_NC0
  7  NC1  TRI  = NC_INA230_6_NC1
  8  NC2  TRI  = NC_INA230_6_NC2
  9  VCC  POWER  = P3V3_AUX
  10  GND  POWER  = GND
  11  VBUS  POWER  = P12V_OCP_SFF
  12  VINM  IN  = VSENSE_P12V_INA230_6_INN
  13  VINP  IN  = VSENSE_P12V_INA230_6_INP
  14  NC3  TRI  = NC_INA230_6_NC3
  15  NC4  TRI  = NC_INA230_6_NC4
  16  NC5  TRI  = NC_INA230_6_NC5
  TH  TH_GND  POWER  = GND
